# T6G (Grand Teton) — schematic netlist excerpt (pin names and nets, part order shuffled) for the footprints in the layout excerpt that follows; sources: Cadence DE-HDL packaged netlist, KiCad conversion of 04192023_DAF0TMB3IC0_F0TG_MB_C_brd_V02_OCP.brd

PR836  Q_RES  1K 1% CHIP  pkg 0402LF  page 190 : A = P3V3_AUX_VOS ; B = P3V3_AUX
C3928  Q_CAP  22UF 4V 20% X6S  pkg C0402  page 70 : A = PVDDCR_SOC_P0 ; B = GND

(kicad_pcb
	(version 20260206)
	(generator "pcbnew")
	(generator_version "10.0")
	(general
		(thickness 1.6)
		(legacy_teardrops no)
	)
	(paper "A4")
	(title_block
		(title "04192023_DAF0TMB3IC0_F0TG_MB_C_brd_V02_OCP.brd")
		(comment 1 "Grand Teton / footprints 1869-1870 of 8354")
	)
	(layers
		(0 "F.Cu" signal "TOP")
		(4 "In1.Cu" signal "GND")
		(6 "In2.Cu" signal "IN1")
		(8 "In3.Cu" signal "GND1")
		(10 "In4.Cu" signal "IN2")
		(12 "In5.Cu" signal "GND2")
		(14 "In6.Cu" signal "IN3")
		(16 "In7.Cu" signal "GND3")
		(18 "In8.Cu" signal "VCC")
		(20 "In9.Cu" signal "VCC1")
		(22 "In10.Cu" signal "GND4")
		(24 "In11.Cu" signal "IN4")
		(26 "In12.Cu" signal "GND5")
		(28 "In13.Cu" signal "IN5")
		(30 "In14.Cu" signal "GND6")
		(32 "In15.Cu" signal "IN6")
		(34 "In16.Cu" signal "GND7")
		(2 "B.Cu" signal "BOTTOM")
		(9 "F.Adhes" user "F.Adhesive")
		(11 "B.Adhes" user "B.Adhesive")
		(13 "F.Paste" user "Package Geometry/Pastemask Top")
		(15 "B.Paste" user "Package Geometry/Pastemask Bottom")
		(5 "F.SilkS" user "Ref Des/Silkscreen Top")
		(7 "B.SilkS" user "Ref Des/Silkscreen Bottom")
		(1 "F.Mask" user "Board Geometry/Soldermask Top")
		(3 "B.Mask" user "Board Geometry/Soldermask Bottom")
		(17 "Dwgs.User" user "User.Drawings")
		(19 "Cmts.User" user "User.Comments")
		(21 "Eco1.User" user "User.Eco1")
		(23 "Eco2.User" user "User.Eco2")
		(25 "Edge.Cuts" user "Board Geometry/Outline")
		(27 "Margin" user)
		(31 "F.CrtYd" user "Package Geometry/Place Bound Top")
		(29 "B.CrtYd" user "Package Geometry/Place Bound Bottom")
		(35 "F.Fab" user "Ref Des/Assembly Top")
		(33 "B.Fab" user "Ref Des/Assembly Bottom")
	)
	(footprint ""
		(layer "F.Cu")
		(at 358.465882 -256.012188 90)
		(property "Reference" "C3928"
			(at 0 0 90)
			(layer "F.SilkS")
			(hide yes)
			(effects
				(font
					(size 1.27 1.27)
				)
			)
		)
		(property "Value" ""
			(at 0 0 90)
			(layer "F.Fab")
			(effects
				(font
					(size 1.27 1.27)
				)
			)
		)
		(duplicate_pad_numbers_are_jumpers no)
		(fp_line
			(start 0.7874 -0.4064)
			(end 0.7874 0.4064)
			(stroke
				(width 0.1524)
				(type default)
			)
			(layer "F.SilkS")
		)
		(fp_line
			(start -0.7874 -0.4064)
			(end 0.7874 -0.4064)
			(stroke
				(width 0.1524)
				(type default)
			)
			(layer "F.SilkS")
		)
		(fp_line
			(start 0.7874 0.4064)
			(end -0.7874 0.4064)
			(stroke
				(width 0.1524)
				(type default)
			)
			(layer "F.SilkS")
		)
		(fp_line
			(start -0.7874 0.4064)
			(end -0.7874 -0.4064)
			(stroke
				(width 0.1524)
				(type default)
			)
			(layer "F.SilkS")
		)
		(fp_line
			(start -0.12065 -0.305054)
			(end -0.12065 -0.2794)
			(stroke
				(width 0.1)
				(type default)
			)
			(layer "F.Fab")
		)
		(fp_line
			(start -0.67945 -0.305054)
			(end -0.12065 -0.305054)
			(stroke
				(width 0.1)
				(type default)
			)
			(layer "F.Fab")
		)
		(fp_line
			(start 0.67945 -0.3048)
			(end 0.67945 0.3048)
			(stroke
				(width 0.1)
				(type default)
			)
			(layer "F.Fab")
		)
		(fp_line
			(start 0.12065 -0.3048)
			(end 0.67945 -0.3048)
			(stroke
				(width 0.1)
				(type default)
			)
			(layer "F.Fab")
		)
		(fp_line
			(start 0.12065 -0.2794)
			(end 0.12065 -0.3048)
			(stroke
				(width 0.1)
				(type default)
			)
			(layer "F.Fab")
		)
		(fp_line
			(start -0.12065 -0.2794)
			(end 0.12065 -0.2794)
			(stroke
				(width 0.1)
				(type default)
			)
			(layer "F.Fab")
		)
		(fp_line
			(start 0.120396 0.2794)
			(end -0.12065 0.2794)
			(stroke
				(width 0.1)
				(type default)
			)
			(layer "F.Fab")
		)
		(fp_line
			(start -0.12065 0.2794)
			(end -0.12065 0.3048)
			(stroke
				(width 0.1)
				(type default)
			)
			(layer "F.Fab")
		)
		(fp_line
			(start 0.67945 0.3048)
			(end 0.120396 0.3048)
			(stroke
				(width 0.1)
				(type default)
			)
			(layer "F.Fab")
		)
		(fp_line
			(start 0.120396 0.3048)
			(end 0.120396 0.2794)
			(stroke
				(width 0.1)
				(type default)
			)
			(layer "F.Fab")
		)
		(fp_line
			(start -0.12065 0.3048)
			(end -0.67945 0.3048)
			(stroke
				(width 0.1)
				(type default)
			)
			(layer "F.Fab")
		)
		(fp_line
			(start -0.67945 0.3048)
			(end -0.67945 -0.305054)
			(stroke
				(width 0.1)
				(type default)
			)
			(layer "F.Fab")
		)
		(pad "1" smd circle
			(at -0.40005 0 90)
			(size 0 0)
			(layers "F.Cu" "F.Mask" "F.Paste")
			(net "PVDDCR_SOC_P0")
		)
		(pad "2" smd circle
			(at 0.40005 0 90)
			(size 0 0)
			(layers "F.Cu" "F.Mask" "F.Paste")
			(net "GND")
		)
	)
	(footprint ""
		(layer "F.Cu")
		(at 452.756016 -46.345602 180)
		(property "Reference" "PR836"
			(at 0 0 180)
			(layer "F.SilkS")
			(hide yes)
			(effects
				(font
					(size 1.27 1.27)
				)
			)
		)
		(property "Value" ""
			(at 0 0 180)
			(layer "F.Fab")
			(effects
				(font
					(size 1.27 1.27)
				)
			)
		)
		(duplicate_pad_numbers_are_jumpers no)
		(fp_line
			(start 0.7874 0.4064)
			(end -0.7874 0.4064)
			(stroke
				(width 0.1524)
				(type default)
			)
			(layer "F.SilkS")
		)
		(fp_line
			(start 0.7874 -0.4064)
			(end 0.7874 0.4064)
			(stroke
				(width 0.1524)
				(type default)
			)
			(layer "F.SilkS")
		)
		(fp_line
			(start -0.7874 0.4064)
			(end -0.7874 -0.4064)
			(stroke
				(width 0.1524)
				(type default)
			)
			(layer "F.SilkS")
		)
		(fp_line
			(start -0.7874 -0.4064)
			(end 0.7874 -0.4064)
			(stroke
				(width 0.1524)
				(type default)
			)
			(layer "F.SilkS")
		)
		(fp_line
			(start 0.67945 0.3048)
			(end 0.120396 0.3048)
			(stroke
				(width 0.1)
				(type default)
			)
			(layer "F.Fab")
		)
		(fp_line
			(start 0.67945 -0.3048)
			(end 0.67945 0.3048)
			(stroke
				(width 0.1)
				(type default)
			)
			(layer "F.Fab")
		)
		(fp_line
			(start 0.12065 -0.2794)
			(end 0.12065 -0.3048)
			(stroke
				(width 0.1)
				(type default)
			)
			(layer "F.Fab")
		)
		(fp_line
			(start 0.12065 -0.3048)
			(end 0.67945 -0.3048)
			(stroke
				(width 0.1)
				(type default)
			)
			(layer "F.Fab")
		)
		(fp_line
			(start 0.120396 0.3048)
			(end 0.120396 0.2794)
			(stroke
				(width 0.1)
				(type default)
			)
			(layer "F.Fab")
		)
		(fp_line
			(start 0.120396 0.2794)
			(end -0.12065 0.2794)
			(stroke
				(width 0.1)
				(type default)
			)
			(layer "F.Fab")
		)
		(fp_line
			(start -0.12065 0.3048)
			(end -0.67945 0.3048)
			(stroke
				(width 0.1)
				(type default)
			)
			(layer "F.Fab")
		)
		(fp_line
			(start -0.12065 0.2794)
			(end -0.12065 0.3048)
			(stroke
				(width 0.1)
				(type default)
			)
			(layer "F.Fab")
		)
		(fp_line
			(start -0.12065 -0.2794)
			(end 0.12065 -0.2794)
			(stroke
				(width 0.1)
				(type default)
			)
			(layer "F.Fab")
		)
		(fp_line
			(start -0.12065 -0.305054)
			(end -0.12065 -0.2794)
			(stroke
				(width 0.1)
				(type default)
			)
			(layer "F.Fab")
		)
		(fp_line
			(start -0.67945 0.3048)
			(end -0.67945 -0.305054)
			(stroke
				(width 0.1)
				(type default)
			)
			(layer "F.Fab")
		)
		(fp_line
			(start -0.67945 -0.305054)
			(end -0.12065 -0.305054)
			(stroke
				(width 0.1)
				(type default)
			)
			(layer "F.Fab")
		)
		(pad "1" smd circle
			(at -0.40005 0 180)
			(size 0 0)
			(layers "F.Cu" "F.Mask" "F.Paste")
			(net "P3V3_AUX_VOS")
		)
		(pad "2" smd circle
			(at 0.40005 0 180)
			(size 0 0)
			(layers "F.Cu" "F.Mask" "F.Paste")
			(net "P3V3_AUX")
		)
	)
)
